(kicad_pcb
	(version 20260206)
	(generator "pcbnew")
	(generator_version "10.0")
	(general
		(thickness 1.6)
		(legacy_teardrops no)
	)
	(paper "A4")
	(title_block
		(title "pdpb — Lightning_PDPB_BRD.brd")
		(comment 1 "Lightning (Wiwynn / Facebook NVMe JBOF) / footprints 297-302 of 1140")
	)
	(layers
		(0 "F.Cu" signal "TOP")
		(4 "In1.Cu" signal "L2GND")
		(6 "In2.Cu" signal "L3")
		(8 "In3.Cu" signal "L4VCC")
		(10 "In4.Cu" signal "L5VCC")
		(12 "In5.Cu" signal "L6")
		(14 "In6.Cu" signal "L7GND")
		(2 "B.Cu" signal "BOTTOM")
		(9 "F.Adhes" user "F.Adhesive")
		(11 "B.Adhes" user "B.Adhesive")
		(13 "F.Paste" user "Package Geometry/Pastemask Top")
		(15 "B.Paste" user "Package Geometry/Pastemask Bottom")
		(5 "F.SilkS" user "Ref Des/Silkscreen Top")
		(7 "B.SilkS" user "Ref Des/Silkscreen Bottom")
		(1 "F.Mask" user "Board Geometry/Soldermask Top")
		(3 "B.Mask" user "Board Geometry/Soldermask Bottom")
		(17 "Dwgs.User" user "User.Drawings")
		(19 "Cmts.User" user "User.Comments")
		(21 "Eco1.User" user "User.Eco1")
		(23 "Eco2.User" user "User.Eco2")
		(25 "Edge.Cuts" user "Board Geometry/Outline")
		(27 "Margin" user)
		(31 "F.CrtYd" user "Package Geometry/Place Bound Top")
		(29 "B.CrtYd" user "Package Geometry/Place Bound Bottom")
		(35 "F.Fab" user "Ref Des/Assembly Top")
		(33 "B.Fab" user "Ref Des/Assembly Bottom")
	)
	(footprint ""
		(layer "F.Cu")
		(at 33.999932 -4.500118)
		(property "Reference" "H13"
			(at 0 0 0)
			(layer "F.SilkS")
			(hide yes)
			(effects
				(font
					(size 1.27 1.27)
				)
			)
		)
		(property "Value" "GEN276X162R197X296-6-F-A-GP"
			(at -6.7183 4.1402 0)
			(unlocked yes)
			(layer "F.Fab")
			(hide yes)
			(effects
				(font
					(size 1.016 1.016)
					(thickness 0.1524)
				)
			)
		)
		(property "Device Type" "GEN276X162R197X296-6-F-A"
			(at -6.7183 2.6162 0)
			(unlocked yes)
			(layer "F.Fab")
			(hide yes)
			(effects
				(font
					(size 1.016 1.016)
					(thickness 0.1524)
				)
			)
		)
		(duplicate_pad_numbers_are_jumpers no)
		(fp_poly
			(pts
				(arc
					(start 2.723642 4.777232)
					(mid -0.000169 6.508462)
					(end -2.723896 4.776978)
				)
				(arc
					(start -2.723896 4.776978)
					(mid 0.000173 -5.499012)
					(end 2.723642 4.777232)
				)
			)
			(stroke
				(width 0)
				(type default)
			)
			(fill no)
			(layer "B.CrtYd")
		)
		(fp_poly
			(pts
				(arc
					(start 2.723642 4.777232)
					(mid -0.000169 6.508462)
					(end -2.723896 4.776978)
				)
				(arc
					(start -2.723896 4.776978)
					(mid 0.000173 -5.499012)
					(end 2.723642 4.777232)
				)
			)
			(stroke
				(width 0)
				(type default)
			)
			(fill no)
			(layer "F.CrtYd")
		)
		(fp_poly
			(pts
				(arc
					(start 2.723642 4.777232)
					(mid -0.000169 6.508462)
					(end -2.723896 4.776978)
				)
				(arc
					(start -2.723896 4.776978)
					(mid 0.000173 -5.499012)
					(end 2.723642 4.777232)
				)
			)
			(stroke
				(width 0)
				(type default)
			)
			(fill no)
			(layer "B.Fab")
		)
		(fp_poly
			(pts
				(arc
					(start 2.723642 4.777232)
					(mid -0.000169 6.508462)
					(end -2.723896 4.776978)
				)
				(arc
					(start -2.723896 4.776978)
					(mid 0.000173 -5.499012)
					(end 2.723642 4.777232)
				)
			)
			(stroke
				(width 0)
				(type default)
			)
			(fill no)
			(layer "F.Fab")
		)
		(pad "" np_thru_hole circle
			(at 0 0)
			(size 0.254 0.254)
			(drill 0.0254)
			(layers "*.Cu" "*.Mask")
			(clearance 3.135376)
			(thermal_gap 3.135376)
		)
		(pad "1" thru_hole circle
			(at 2.549906 0)
			(size 0.8636 0.8636)
			(drill 0.508)
			(layers "*.Cu" "*.Mask")
			(remove_unused_layers no)
			(net "GND")
			(clearance 0.8255)
			(thermal_gap 0.8255)
		)
		(pad "2" thru_hole circle
			(at 2.210054 -1.27)
			(size 0.8636 0.8636)
			(drill 0.508)
			(layers "*.Cu" "*.Mask")
			(remove_unused_layers no)
			(net "GND")
			(clearance 0.8255)
			(thermal_gap 0.8255)
		)
		(pad "3" thru_hole circle
			(at 1.27 -2.210054)
			(size 0.8636 0.8636)
			(drill 0.508)
			(layers "*.Cu" "*.Mask")
			(remove_unused_layers no)
			(net "GND")
			(clearance 0.8255)
			(thermal_gap 0.8255)
		)
		(pad "4" thru_hole circle
			(at -1.279906 -2.210054)
			(size 0.8636 0.8636)
			(drill 0.508)
			(layers "*.Cu" "*.Mask")
			(remove_unused_layers no)
			(net "GND")
			(clearance 0.8255)
			(thermal_gap 0.8255)
		)
		(pad "5" thru_hole circle
			(at -2.210054 -1.27)
			(size 0.8636 0.8636)
			(drill 0.508)
			(layers "*.Cu" "*.Mask")
			(remove_unused_layers no)
			(net "GND")
			(clearance 0.8255)
			(thermal_gap 0.8255)
		)
		(pad "6" thru_hole circle
			(at -2.549906 0)
			(size 0.8636 0.8636)
			(drill 0.508)
			(layers "*.Cu" "*.Mask")
			(remove_unused_layers no)
			(net "GND")
			(clearance 0.8255)
			(thermal_gap 0.8255)
		)
		(zone
			(layers "F.Cu" "B.Cu" "In1.Cu" "In2.Cu" "In3.Cu" "In4.Cu" "In5.Cu" "In6.Cu")
			(hatch none 0.5)
			(connect_pads
				(clearance 0)
			)
			(min_thickness 0.25)
			(keepout
				(tracks allowed)
				(vias not_allowed)
				(pads allowed)
				(copperpour not_allowed)
				(footprints allowed)
			)
			(placement
				(enabled no)
				(sheetname "")
			)
			(fill
				(thermal_gap 0.5)
				(thermal_bridge_width 0.5)
				(island_removal_mode 0)
			)
			(polygon
				(pts
					(arc
						(start 38.317932 -4.503166)
						(mid 29.681932 -4.503166)
						(end 38.317932 -4.503166)
					)
				)
			)
		)
		(zone
			(layers "F.Cu" "B.Cu" "In1.Cu" "In2.Cu" "In3.Cu" "In4.Cu" "In5.Cu" "In6.Cu")
			(hatch none 0.5)
			(connect_pads
				(clearance 0)
			)
			(min_thickness 0.25)
			(keepout
				(tracks not_allowed)
				(vias allowed)
				(pads allowed)
				(copperpour not_allowed)
				(footprints allowed)
			)
			(placement
				(enabled no)
				(sheetname "")
			)
			(fill
				(thermal_gap 0.5)
				(thermal_bridge_width 0.5)
				(island_removal_mode 0)
			)
			(polygon
				(pts
					(arc
						(start 36.339272 -2.890774)
						(mid 34.000012 2.008329)
						(end 31.660338 -2.890774)
					)
					(arc
						(start 31.660338 -2.890774)
						(mid 31.906305 -3.33114)
						(end 31.991554 -3.828288)
					)
					(arc
						(start 31.991554 -4.500118)
						(mid 33.999932 -6.508496)
						(end 36.008056 -4.500118)
					)
					(arc
						(start 36.008056 -3.828288)
						(mid 36.093291 -3.331134)
						(end 36.339272 -2.890774)
					)
				)
			)
		)
	)
	(footprint ""
		(layer "F.Cu")
		(at 37.211 -194.3354 180)
		(property "Reference" "PC1217"
			(at 0 0 180)
			(layer "F.SilkS")
			(hide yes)
			(effects
				(font
					(size 1.27 1.27)
				)
			)
		)
		(property "Value" "SCD1U50V3KX-GP"
			(at 0 -2.8194 180)
			(unlocked yes)
			(layer "F.Fab")
			(hide yes)
			(effects
				(font
					(size 1.016 1.016)
					(thickness 0.1524)
				)
			)
		)
		(property "Device Type" "C603H36"
			(at 0 -4.3434 180)
			(unlocked yes)
			(layer "F.Fab")
			(hide yes)
			(effects
				(font
					(size 1.016 1.016)
					(thickness 0.1524)
				)
			)
		)
		(duplicate_pad_numbers_are_jumpers no)
		(fp_line
			(start 0.508 0)
			(end -0.508 0)
			(stroke
				(width 0.2032)
				(type default)
			)
			(layer "F.SilkS")
		)
		(fp_rect
			(start -0.5842 1.3335)
			(end 0.5842 -1.3335)
			(stroke
				(width 0)
				(type default)
			)
			(fill no)
			(layer "F.CrtYd")
		)
		(fp_rect
			(start -0.5842 1.3335)
			(end 0.5842 -1.3335)
			(stroke
				(width 0)
				(type default)
			)
			(fill no)
			(layer "F.Fab")
		)
		(pad "1" smd custom
			(at 0 -0.762 180)
			(size 0.2159 0.2159)
			(layers "F.Cu" "F.Mask" "F.Paste")
			(net "P12V_SSD8")
			(options
				(clearance outline)
				(anchor circle)
			)
			(primitives
				(gr_poly
					(pts
						(arc
							(start -0.3302 -0.4318)
							(mid -0.402042 -0.402042)
							(end -0.4318 -0.3302)
						)
						(arc
							(start -0.4318 0.3302)
							(mid -0.402042 0.402042)
							(end -0.3302 0.4318)
						)
						(arc
							(start 0.3302 0.4318)
							(mid 0.402042 0.402042)
							(end 0.4318 0.3302)
						)
						(arc
							(start 0.4318 -0.3302)
							(mid 0.402042 -0.402042)
							(end 0.3302 -0.4318)
						)
					)
					(width 0)
					(fill yes)
				)
			)
		)
		(pad "2" smd custom
			(at 0 0.762 180)
			(size 0.2159 0.2159)
			(layers "F.Cu" "F.Mask" "F.Paste")
			(net "GND")
			(options
				(clearance outline)
				(anchor circle)
			)
			(primitives
				(gr_poly
					(pts
						(arc
							(start -0.3302 -0.4318)
							(mid -0.402042 -0.402042)
							(end -0.4318 -0.3302)
						)
						(arc
							(start -0.4318 0.3302)
							(mid -0.402042 0.402042)
							(end -0.3302 0.4318)
						)
						(arc
							(start 0.3302 0.4318)
							(mid 0.402042 0.402042)
							(end 0.4318 0.3302)
						)
						(arc
							(start 0.4318 -0.3302)
							(mid 0.402042 -0.402042)
							(end 0.3302 -0.4318)
						)
					)
					(width 0)
					(fill yes)
				)
			)
		)
	)
	(footprint ""
		(layer "F.Cu")
		(at 100.33 -296.545)
		(property "Reference" "R9077"
			(at 0 0 0)
			(layer "F.SilkS")
			(hide yes)
			(effects
				(font
					(size 1.27 1.27)
				)
			)
		)
		(property "Value" "27R2F-GP"
			(at 0.064008 -3.993896 0)
			(unlocked yes)
			(layer "F.Fab")
			(hide yes)
			(effects
				(font
					(size 1.016 1.016)
					(thickness 0.1524)
				)
			)
		)
		(property "Device Type" "R402H16"
			(at 0.064008 -5.517896 0)
			(unlocked yes)
			(layer "F.Fab")
			(hide yes)
			(effects
				(font
					(size 1.016 1.016)
					(thickness 0.1524)
				)
			)
		)
		(duplicate_pad_numbers_are_jumpers no)
		(fp_line
			(start -0.508 -0.9398)
			(end -0.508 0.9398)
			(stroke
				(width 0.1524)
				(type default)
			)
			(layer "F.SilkS")
		)
		(fp_line
			(start 0.508 -0.9398)
			(end -0.508 -0.9398)
			(stroke
				(width 0.1524)
				(type default)
			)
			(layer "F.SilkS")
		)
		(fp_rect
			(start -0.508 0.9398)
			(end 0.508 -0.9398)
			(stroke
				(width 0)
				(type default)
			)
			(fill no)
			(layer "F.CrtYd")
		)
		(fp_rect
			(start -0.508 0.9398)
			(end 0.508 -0.9398)
			(stroke
				(width 0)
				(type default)
			)
			(fill no)
			(layer "F.Fab")
		)
		(pad "1" smd custom
			(at 0 -0.4445)
			(size 0.1397 0.1397)
			(layers "F.Cu" "F.Mask" "F.Paste")
			(net "PE_CLK_100M_DR2_1_R_N")
			(options
				(clearance outline)
				(anchor circle)
			)
			(primitives
				(gr_poly
					(pts
						(arc
							(start -0.1778 -0.2794)
							(mid -0.249642 -0.249642)
							(end -0.2794 -0.1778)
						)
						(arc
							(start -0.2794 0.1778)
							(mid -0.249642 0.249642)
							(end -0.1778 0.2794)
						)
						(arc
							(start 0.1778 0.2794)
							(mid 0.249642 0.249642)
							(end 0.2794 0.1778)
						)
						(arc
							(start 0.2794 -0.1778)
							(mid 0.249642 -0.249642)
							(end 0.1778 -0.2794)
						)
					)
					(width 0)
					(fill yes)
				)
			)
		)
		(pad "2" smd custom
			(at 0 0.4445)
			(size 0.1397 0.1397)
			(layers "F.Cu" "F.Mask" "F.Paste")
			(net "PE_CLK100M_DR2_1_N")
			(options
				(clearance outline)
				(anchor circle)
			)
			(primitives
				(gr_poly
					(pts
						(arc
							(start -0.1778 -0.2794)
							(mid -0.249642 -0.249642)
							(end -0.2794 -0.1778)
						)
						(arc
							(start -0.2794 0.1778)
							(mid -0.249642 0.249642)
							(end -0.1778 0.2794)
						)
						(arc
							(start 0.1778 0.2794)
							(mid 0.249642 0.249642)
							(end 0.2794 0.1778)
						)
						(arc
							(start 0.2794 -0.1778)
							(mid 0.249642 -0.249642)
							(end 0.1778 -0.2794)
						)
					)
					(width 0)
					(fill yes)
				)
			)
		)
	)
	(footprint ""
		(layer "F.Cu")
		(at 49.4665 -445.7065)
		(property "Reference" "R9817"
			(at 0 0 0)
			(layer "F.SilkS")
			(hide yes)
			(effects
				(font
					(size 1.27 1.27)
				)
			)
		)
		(property "Value" "0R2J-2-GP"
			(at 0.064008 -3.993896 0)
			(unlocked yes)
			(layer "F.Fab")
			(hide yes)
			(effects
				(font
					(size 1.016 1.016)
					(thickness 0.1524)
				)
			)
		)
		(property "Device Type" "R402H16"
			(at 0.064008 -5.517896 0)
			(unlocked yes)
			(layer "F.Fab")
			(hide yes)
			(effects
				(font
					(size 1.016 1.016)
					(thickness 0.1524)
				)
			)
		)
		(duplicate_pad_numbers_are_jumpers no)
		(fp_line
			(start -0.508 -0.9398)
			(end -0.508 0.9398)
			(stroke
				(width 0.1524)
				(type default)
			)
			(layer "F.SilkS")
		)
		(fp_line
			(start 0.508 -0.9398)
			(end -0.508 -0.9398)
			(stroke
				(width 0.1524)
				(type default)
			)
			(layer "F.SilkS")
		)
		(fp_rect
			(start -0.508 0.9398)
			(end 0.508 -0.9398)
			(stroke
				(width 0)
				(type default)
			)
			(fill no)
			(layer "F.CrtYd")
		)
		(fp_rect
			(start -0.508 0.9398)
			(end 0.508 -0.9398)
			(stroke
				(width 0)
				(type default)
			)
			(fill no)
			(layer "F.Fab")
		)
		(pad "1" smd custom
			(at 0 -0.4445)
			(size 0.1397 0.1397)
			(layers "F.Cu" "F.Mask" "F.Paste")
			(net "SSD_ACT_DR5_R")
			(options
				(clearance outline)
				(anchor circle)
			)
			(primitives
				(gr_poly
					(pts
						(arc
							(start -0.1778 -0.2794)
							(mid -0.249642 -0.249642)
							(end -0.2794 -0.1778)
						)
						(arc
							(start -0.2794 0.1778)
							(mid -0.249642 0.249642)
							(end -0.1778 0.2794)
						)
						(arc
							(start 0.1778 0.2794)
							(mid 0.249642 0.249642)
							(end 0.2794 0.1778)
						)
						(arc
							(start 0.2794 -0.1778)
							(mid 0.249642 -0.249642)
							(end 0.1778 -0.2794)
						)
					)
					(width 0)
					(fill yes)
				)
			)
		)
		(pad "2" smd custom
			(at 0 0.4445)
			(size 0.1397 0.1397)
			(layers "F.Cu" "F.Mask" "F.Paste")
			(net "SSD_ACT_DR5")
			(options
				(clearance outline)
				(anchor circle)
			)
			(primitives
				(gr_poly
					(pts
						(arc
							(start -0.1778 -0.2794)
							(mid -0.249642 -0.249642)
							(end -0.2794 -0.1778)
						)
						(arc
							(start -0.2794 0.1778)
							(mid -0.249642 0.249642)
							(end -0.1778 0.2794)
						)
						(arc
							(start 0.1778 0.2794)
							(mid 0.249642 0.249642)
							(end 0.2794 0.1778)
						)
						(arc
							(start 0.2794 -0.1778)
							(mid 0.249642 -0.249642)
							(end 0.1778 -0.2794)
						)
					)
					(width 0)
					(fill yes)
				)
			)
		)
	)
	(footprint ""
		(layer "F.Cu")
		(at 84.455 -424.942 -90)
		(property "Reference" "R9033"
			(at 0 0 270)
			(layer "F.SilkS")
			(hide yes)
			(effects
				(font
					(size 1.27 1.27)
				)
			)
		)
		(property "Value" "4K7R2F-GP"
			(at 0.064008 -3.993896 270)
			(unlocked yes)
			(layer "F.Fab")
			(hide yes)
			(effects
				(font
					(size 1.016 1.016)
					(thickness 0.1524)
				)
			)
		)
		(property "Device Type" "R402H16"
			(at 0.064008 -5.517896 270)
			(unlocked yes)
			(layer "F.Fab")
			(hide yes)
			(effects
				(font
					(size 1.016 1.016)
					(thickness 0.1524)
				)
			)
		)
		(duplicate_pad_numbers_are_jumpers no)
		(fp_line
			(start -0.508 -0.9398)
			(end -0.508 0.9398)
			(stroke
				(width 0.1524)
				(type default)
			)
			(layer "F.SilkS")
		)
		(fp_line
			(start 0.508 -0.9398)
			(end -0.508 -0.9398)
			(stroke
				(width 0.1524)
				(type default)
			)
			(layer "F.SilkS")
		)
		(fp_rect
			(start -0.508 0.9398)
			(end 0.508 -0.9398)
			(stroke
				(width 0)
				(type default)
			)
			(fill no)
			(layer "F.CrtYd")
		)
		(fp_rect
			(start -0.508 0.9398)
			(end 0.508 -0.9398)
			(stroke
				(width 0)
				(type default)
			)
			(fill no)
			(layer "F.Fab")
		)
		(pad "1" smd custom
			(at 0 -0.4445 270)
			(size 0.1397 0.1397)
			(layers "F.Cu" "F.Mask" "F.Paste")
			(net "CLK_BUF_EU1_SMB_A1_TRI")
			(options
				(clearance outline)
				(anchor circle)
			)
			(primitives
				(gr_poly
					(pts
						(arc
							(start -0.1778 -0.2794)
							(mid -0.249642 -0.249642)
							(end -0.2794 -0.1778)
						)
						(arc
							(start -0.2794 0.1778)
							(mid -0.249642 0.249642)
							(end -0.1778 0.2794)
						)
						(arc
							(start 0.1778 0.2794)
							(mid 0.249642 0.249642)
							(end 0.2794 0.1778)
						)
						(arc
							(start 0.2794 -0.1778)
							(mid 0.249642 -0.249642)
							(end 0.1778 -0.2794)
						)
					)
					(width 0)
					(fill yes)
				)
			)
		)
		(pad "2" smd custom
			(at 0 0.4445 270)
			(size 0.1397 0.1397)
			(layers "F.Cu" "F.Mask" "F.Paste")
			(net "GND")
			(options
				(clearance outline)
				(anchor circle)
			)
			(primitives
				(gr_poly
					(pts
						(arc
							(start -0.1778 -0.2794)
							(mid -0.249642 -0.249642)
							(end -0.2794 -0.1778)
						)
						(arc
							(start -0.2794 0.1778)
							(mid -0.249642 0.249642)
							(end -0.1778 0.2794)
						)
						(arc
							(start 0.1778 0.2794)
							(mid 0.249642 0.249642)
							(end 0.2794 0.1778)
						)
						(arc
							(start 0.2794 -0.1778)
							(mid 0.249642 -0.249642)
							(end 0.1778 -0.2794)
						)
					)
					(width 0)
					(fill yes)
				)
			)
		)
	)
	(footprint ""
		(layer "F.Cu")
		(at 73.152 -444.246)
		(property "Reference" "C346"
			(at 0 0 0)
			(layer "F.SilkS")
			(hide yes)
			(effects
				(font
					(size 1.27 1.27)
				)
			)
		)
		(property "Value" "SC1U16V3KX-5GP"
			(at 0 -2.8194 0)
			(unlocked yes)
			(layer "F.Fab")
			(hide yes)
			(effects
				(font
					(size 1.016 1.016)
					(thickness 0.1524)
				)
			)
		)
		(property "Device Type" "C603H36"
			(at 0 -4.3434 0)
			(unlocked yes)
			(layer "F.Fab")
			(hide yes)
			(effects
				(font
					(size 1.016 1.016)
					(thickness 0.1524)
				)
			)
		)
		(duplicate_pad_numbers_are_jumpers no)
		(fp_line
			(start 0.508 0)
			(end -0.508 0)
			(stroke
				(width 0.2032)
				(type default)
			)
			(layer "F.SilkS")
		)
		(fp_rect
			(start -0.5842 1.3335)
			(end 0.5842 -1.3335)
			(stroke
				(width 0)
				(type default)
			)
			(fill no)
			(layer "F.CrtYd")
		)
		(fp_rect
			(start -0.5842 1.3335)
			(end 0.5842 -1.3335)
			(stroke
				(width 0)
				(type default)
			)
			(fill no)
			(layer "F.Fab")
		)
		(pad "1" smd custom
			(at 0 -0.762)
			(size 0.2159 0.2159)
			(layers "F.Cu" "F.Mask" "F.Paste")
			(net "P3V3")
			(options
				(clearance outline)
				(anchor circle)
			)
			(primitives
				(gr_poly
					(pts
						(arc
							(start -0.3302 -0.4318)
							(mid -0.402042 -0.402042)
							(end -0.4318 -0.3302)
						)
						(arc
							(start -0.4318 0.3302)
							(mid -0.402042 0.402042)
							(end -0.3302 0.4318)
						)
						(arc
							(start 0.3302 0.4318)
							(mid 0.402042 0.402042)
							(end 0.4318 0.3302)
						)
						(arc
							(start 0.4318 -0.3302)
							(mid 0.402042 -0.402042)
							(end 0.3302 -0.4318)
						)
					)
					(width 0)
					(fill yes)
				)
			)
		)
		(pad "2" smd custom
			(at 0 0.762)
			(size 0.2159 0.2159)
			(layers "F.Cu" "F.Mask" "F.Paste")
			(net "GND")
			(options
				(clearance outline)
				(anchor circle)
			)
			(primitives
				(gr_poly
					(pts
						(arc
							(start -0.3302 -0.4318)
							(mid -0.402042 -0.402042)
							(end -0.4318 -0.3302)
						)
						(arc
							(start -0.4318 0.3302)
							(mid -0.402042 0.402042)
							(end -0.3302 0.4318)
						)
						(arc
							(start 0.3302 0.4318)
							(mid 0.402042 0.402042)
							(end 0.4318 0.3302)
						)
						(arc
							(start 0.4318 -0.3302)
							(mid 0.402042 -0.402042)
							(end 0.3302 -0.4318)
						)
					)
					(width 0)
					(fill yes)
				)
			)
		)
	)
)
